(kicad_pcb
	(version 20260206)
	(generator "pcbnew")
	(generator_version "10.0")
	(general
		(thickness 1.6)
		(legacy_teardrops no)
	)
	(paper "A4")
	(title_block
		(title "peb — Lightning_PEB_BRD.brd")
		(comment 1 "Lightning (Wiwynn / Facebook NVMe JBOF) / footprints 2199-2206 of 2563")
	)
	(layers
		(0 "F.Cu" signal "TOP")
		(4 "In1.Cu" signal "L2GND")
		(6 "In2.Cu" signal "L3")
		(8 "In3.Cu" signal "L4VCC")
		(10 "In4.Cu" signal "L5VCC")
		(12 "In5.Cu" signal "L6")
		(14 "In6.Cu" signal "L7GND")
		(2 "B.Cu" signal "BOTTOM")
		(9 "F.Adhes" user "F.Adhesive")
		(11 "B.Adhes" user "B.Adhesive")
		(13 "F.Paste" user "Package Geometry/Pastemask Top")
		(15 "B.Paste" user "Package Geometry/Pastemask Bottom")
		(5 "F.SilkS" user "Ref Des/Silkscreen Top")
		(7 "B.SilkS" user "Ref Des/Silkscreen Bottom")
		(1 "F.Mask" user "Board Geometry/Soldermask Top")
		(3 "B.Mask" user "Board Geometry/Soldermask Bottom")
		(17 "Dwgs.User" user "User.Drawings")
		(19 "Cmts.User" user "User.Comments")
		(21 "Eco1.User" user "User.Eco1")
		(23 "Eco2.User" user "User.Eco2")
		(25 "Edge.Cuts" user "Board Geometry/Outline")
		(27 "Margin" user)
		(31 "F.CrtYd" user "Package Geometry/Place Bound Top")
		(29 "B.CrtYd" user "Package Geometry/Place Bound Bottom")
		(35 "F.Fab" user "Ref Des/Assembly Top")
		(33 "B.Fab" user "Ref Des/Assembly Bottom")
	)
	(footprint ""
		(layer "B.Cu")
		(at 237.109 -23.241 180)
		(property "Reference" "R787"
			(at 0 0 0)
			(layer "B.SilkS")
			(hide yes)
			(effects
				(font
					(size 1.27 1.27)
				)
				(justify mirror)
			)
		)
		(property "Value" "4K7R2F-GP"
			(at -0.064008 -3.993896 180)
			(unlocked yes)
			(layer "B.Fab")
			(hide yes)
			(effects
				(font
					(size 1.016 1.016)
					(thickness 0.1524)
				)
				(justify mirror)
			)
		)
		(property "Device Type" "R402H16"
			(at -0.064008 -5.517896 180)
			(unlocked yes)
			(layer "B.Fab")
			(hide yes)
			(effects
				(font
					(size 1.016 1.016)
					(thickness 0.1524)
				)
				(justify mirror)
			)
		)
		(duplicate_pad_numbers_are_jumpers no)
		(fp_line
			(start 0.508 -0.9398)
			(end 0.508 0.9398)
			(stroke
				(width 0.1524)
				(type default)
			)
			(layer "B.SilkS")
		)
		(fp_line
			(start -0.508 -0.9398)
			(end 0.508 -0.9398)
			(stroke
				(width 0.1524)
				(type default)
			)
			(layer "B.SilkS")
		)
		(fp_rect
			(start 0.508 0.9398)
			(end -0.508 -0.9398)
			(stroke
				(width 0)
				(type default)
			)
			(fill no)
			(layer "B.CrtYd")
		)
		(fp_rect
			(start 0.508 0.9398)
			(end -0.508 -0.9398)
			(stroke
				(width 0)
				(type default)
			)
			(fill no)
			(layer "B.Fab")
		)
		(pad "1" smd custom
			(at 0 -0.4445)
			(size 0.1397 0.1397)
			(layers "B.Cu" "B.Mask" "B.Paste")
			(net "BOOTSTRAP7")
			(options
				(clearance outline)
				(anchor circle)
			)
			(primitives
				(gr_poly
					(pts
						(arc
							(start -0.1778 0.2794)
							(mid -0.249642 0.249642)
							(end -0.2794 0.1778)
						)
						(arc
							(start -0.2794 -0.1778)
							(mid -0.249642 -0.249642)
							(end -0.1778 -0.2794)
						)
						(arc
							(start 0.1778 -0.2794)
							(mid 0.249642 -0.249642)
							(end 0.2794 -0.1778)
						)
						(arc
							(start 0.2794 0.1778)
							(mid 0.249642 0.249642)
							(end 0.1778 0.2794)
						)
					)
					(width 0)
					(fill yes)
				)
			)
		)
		(pad "2" smd custom
			(at 0 0.4445)
			(size 0.1397 0.1397)
			(layers "B.Cu" "B.Mask" "B.Paste")
			(net "BOOTSTRAP_R_7")
			(options
				(clearance outline)
				(anchor circle)
			)
			(primitives
				(gr_poly
					(pts
						(arc
							(start -0.1778 0.2794)
							(mid -0.249642 0.249642)
							(end -0.2794 0.1778)
						)
						(arc
							(start -0.2794 -0.1778)
							(mid -0.249642 -0.249642)
							(end -0.1778 -0.2794)
						)
						(arc
							(start 0.1778 -0.2794)
							(mid 0.249642 -0.249642)
							(end 0.2794 -0.1778)
						)
						(arc
							(start 0.2794 0.1778)
							(mid 0.249642 0.249642)
							(end 0.1778 0.2794)
						)
					)
					(width 0)
					(fill yes)
				)
			)
		)
	)
	(footprint ""
		(layer "B.Cu")
		(at 233.59999 -37.999924 90)
		(property "Reference" "TP203"
			(at 0 0 90)
			(layer "B.SilkS")
			(hide yes)
			(effects
				(font
					(size 1.27 1.27)
				)
				(justify mirror)
			)
		)
		(property "Value" "TPAD28-2-GP"
			(at 0.0127 -1.6637 90)
			(unlocked yes)
			(layer "B.Fab")
			(hide yes)
			(effects
				(font
					(size 1.016 1.016)
					(thickness 0.1524)
				)
				(justify mirror)
			)
		)
		(property "Device Type" "TPAD28"
			(at 0.0127 -3.1877 90)
			(unlocked yes)
			(layer "B.Fab")
			(hide yes)
			(effects
				(font
					(size 1.016 1.016)
					(thickness 0.1524)
				)
				(justify mirror)
			)
		)
		(duplicate_pad_numbers_are_jumpers no)
		(fp_poly
			(pts
				(arc
					(start 0 0.3556)
					(mid 0 -0.3556)
					(end 0 0.3556)
				)
			)
			(stroke
				(width 0)
				(type default)
			)
			(fill no)
			(layer "B.CrtYd")
		)
		(fp_poly
			(pts
				(arc
					(start 0 0.6096)
					(mid 0 -0.6096)
					(end 0 0.6096)
				)
			)
			(stroke
				(width 0)
				(type default)
			)
			(fill no)
			(layer "B.Fab")
		)
		(pad "1" smd circle
			(at 0 0 270)
			(size 0.7112 0.7112)
			(layers "B.Cu" "B.Mask" "B.Paste")
			(net "RMII_RXD_1")
		)
	)
	(footprint ""
		(layer "B.Cu")
		(at 228.6254 -59.9948 90)
		(property "Reference" "C539"
			(at 0 0 90)
			(layer "B.SilkS")
			(hide yes)
			(effects
				(font
					(size 1.27 1.27)
				)
				(justify mirror)
			)
		)
		(property "Value" "SCD1U16V1KX-1-GP"
			(at 2.8321 -1.7399 90)
			(unlocked yes)
			(layer "B.Fab")
			(hide yes)
			(effects
				(font
					(size 1.016 1.016)
					(thickness 0.1524)
				)
				(justify mirror)
			)
		)
		(property "Device Type" "C0201H13"
			(at 2.8321 -3.2639 90)
			(unlocked yes)
			(layer "B.Fab")
			(hide yes)
			(effects
				(font
					(size 1.016 1.016)
					(thickness 0.1524)
				)
				(justify mirror)
			)
		)
		(duplicate_pad_numbers_are_jumpers no)
		(fp_rect
			(start 0.2794 0.6477)
			(end -0.2794 -0.6477)
			(stroke
				(width 0)
				(type default)
			)
			(fill no)
			(layer "B.CrtYd")
		)
		(fp_rect
			(start 0.2794 0.6477)
			(end -0.2794 -0.6477)
			(stroke
				(width 0)
				(type default)
			)
			(fill no)
			(layer "B.Fab")
		)
		(pad "1" smd custom
			(at 0 -0.2794 270)
			(size 0.0762 0.0762)
			(layers "B.Cu" "B.Mask" "B.Paste")
			(net "DUT_AVD_PCIE")
			(options
				(clearance outline)
				(anchor circle)
			)
			(primitives
				(gr_poly
					(pts
						(arc
							(start 0.1524 0.127)
							(mid 0.137521 0.162921)
							(end 0.1016 0.1778)
						)
						(arc
							(start -0.1016 0.1778)
							(mid -0.137521 0.162921)
							(end -0.1524 0.127)
						)
						(arc
							(start -0.1524 -0.127)
							(mid -0.137521 -0.162921)
							(end -0.1016 -0.1778)
						)
						(arc
							(start 0.1016 -0.1778)
							(mid 0.137521 -0.162921)
							(end 0.1524 -0.127)
						)
					)
					(width 0)
					(fill yes)
				)
			)
		)
		(pad "2" smd custom
			(at 0 0.2794 270)
			(size 0.0762 0.0762)
			(layers "B.Cu" "B.Mask" "B.Paste")
			(net "GND")
			(options
				(clearance outline)
				(anchor circle)
			)
			(primitives
				(gr_poly
					(pts
						(arc
							(start 0.1524 0.127)
							(mid 0.137521 0.162921)
							(end 0.1016 0.1778)
						)
						(arc
							(start -0.1016 0.1778)
							(mid -0.137521 0.162921)
							(end -0.1524 0.127)
						)
						(arc
							(start -0.1524 -0.127)
							(mid -0.137521 -0.162921)
							(end -0.1016 -0.1778)
						)
						(arc
							(start 0.1016 -0.1778)
							(mid 0.137521 -0.162921)
							(end 0.1524 -0.127)
						)
					)
					(width 0)
					(fill yes)
				)
			)
		)
	)
	(footprint ""
		(layer "B.Cu")
		(at 228.6254 -53.992272 90)
		(property "Reference" "C538"
			(at 0 0 90)
			(layer "B.SilkS")
			(hide yes)
			(effects
				(font
					(size 1.27 1.27)
				)
				(justify mirror)
			)
		)
		(property "Value" "SCD1U16V1KX-1-GP"
			(at 2.8321 -1.7399 90)
			(unlocked yes)
			(layer "B.Fab")
			(hide yes)
			(effects
				(font
					(size 1.016 1.016)
					(thickness 0.1524)
				)
				(justify mirror)
			)
		)
		(property "Device Type" "C0201H13"
			(at 2.8321 -3.2639 90)
			(unlocked yes)
			(layer "B.Fab")
			(hide yes)
			(effects
				(font
					(size 1.016 1.016)
					(thickness 0.1524)
				)
				(justify mirror)
			)
		)
		(duplicate_pad_numbers_are_jumpers no)
		(fp_rect
			(start 0.2794 0.6477)
			(end -0.2794 -0.6477)
			(stroke
				(width 0)
				(type default)
			)
			(fill no)
			(layer "B.CrtYd")
		)
		(fp_rect
			(start 0.2794 0.6477)
			(end -0.2794 -0.6477)
			(stroke
				(width 0)
				(type default)
			)
			(fill no)
			(layer "B.Fab")
		)
		(pad "1" smd custom
			(at 0 -0.2794 270)
			(size 0.0762 0.0762)
			(layers "B.Cu" "B.Mask" "B.Paste")
			(net "DUT_AVD_PCIE")
			(options
				(clearance outline)
				(anchor circle)
			)
			(primitives
				(gr_poly
					(pts
						(arc
							(start 0.1524 0.127)
							(mid 0.137521 0.162921)
							(end 0.1016 0.1778)
						)
						(arc
							(start -0.1016 0.1778)
							(mid -0.137521 0.162921)
							(end -0.1524 0.127)
						)
						(arc
							(start -0.1524 -0.127)
							(mid -0.137521 -0.162921)
							(end -0.1016 -0.1778)
						)
						(arc
							(start 0.1016 -0.1778)
							(mid 0.137521 -0.162921)
							(end 0.1524 -0.127)
						)
					)
					(width 0)
					(fill yes)
				)
			)
		)
		(pad "2" smd custom
			(at 0 0.2794 270)
			(size 0.0762 0.0762)
			(layers "B.Cu" "B.Mask" "B.Paste")
			(net "GND")
			(options
				(clearance outline)
				(anchor circle)
			)
			(primitives
				(gr_poly
					(pts
						(arc
							(start 0.1524 0.127)
							(mid 0.137521 0.162921)
							(end 0.1016 0.1778)
						)
						(arc
							(start -0.1016 0.1778)
							(mid -0.137521 0.162921)
							(end -0.1524 0.127)
						)
						(arc
							(start -0.1524 -0.127)
							(mid -0.137521 -0.162921)
							(end -0.1016 -0.1778)
						)
						(arc
							(start 0.1016 -0.1778)
							(mid 0.137521 -0.162921)
							(end 0.1524 -0.127)
						)
					)
					(width 0)
					(fill yes)
				)
			)
		)
	)
	(footprint ""
		(layer "B.Cu")
		(at 228.6254 -47.997872 90)
		(property "Reference" "C492"
			(at 0 0 90)
			(layer "B.SilkS")
			(hide yes)
			(effects
				(font
					(size 1.27 1.27)
				)
				(justify mirror)
			)
		)
		(property "Value" "SCD1U16V1KX-1-GP"
			(at 2.8321 -1.7399 90)
			(unlocked yes)
			(layer "B.Fab")
			(hide yes)
			(effects
				(font
					(size 1.016 1.016)
					(thickness 0.1524)
				)
				(justify mirror)
			)
		)
		(property "Device Type" "C0201H13"
			(at 2.8321 -3.2639 90)
			(unlocked yes)
			(layer "B.Fab")
			(hide yes)
			(effects
				(font
					(size 1.016 1.016)
					(thickness 0.1524)
				)
				(justify mirror)
			)
		)
		(duplicate_pad_numbers_are_jumpers no)
		(fp_rect
			(start 0.2794 0.6477)
			(end -0.2794 -0.6477)
			(stroke
				(width 0)
				(type default)
			)
			(fill no)
			(layer "B.CrtYd")
		)
		(fp_rect
			(start 0.2794 0.6477)
			(end -0.2794 -0.6477)
			(stroke
				(width 0)
				(type default)
			)
			(fill no)
			(layer "B.Fab")
		)
		(pad "1" smd custom
			(at 0 -0.2794 270)
			(size 0.0762 0.0762)
			(layers "B.Cu" "B.Mask" "B.Paste")
			(net "DUT_AVD_PCIE")
			(options
				(clearance outline)
				(anchor circle)
			)
			(primitives
				(gr_poly
					(pts
						(arc
							(start 0.1524 0.127)
							(mid 0.137521 0.162921)
							(end 0.1016 0.1778)
						)
						(arc
							(start -0.1016 0.1778)
							(mid -0.137521 0.162921)
							(end -0.1524 0.127)
						)
						(arc
							(start -0.1524 -0.127)
							(mid -0.137521 -0.162921)
							(end -0.1016 -0.1778)
						)
						(arc
							(start 0.1016 -0.1778)
							(mid 0.137521 -0.162921)
							(end 0.1524 -0.127)
						)
					)
					(width 0)
					(fill yes)
				)
			)
		)
		(pad "2" smd custom
			(at 0 0.2794 270)
			(size 0.0762 0.0762)
			(layers "B.Cu" "B.Mask" "B.Paste")
			(net "GND")
			(options
				(clearance outline)
				(anchor circle)
			)
			(primitives
				(gr_poly
					(pts
						(arc
							(start 0.1524 0.127)
							(mid 0.137521 0.162921)
							(end 0.1016 0.1778)
						)
						(arc
							(start -0.1016 0.1778)
							(mid -0.137521 0.162921)
							(end -0.1524 0.127)
						)
						(arc
							(start -0.1524 -0.127)
							(mid -0.137521 -0.162921)
							(end -0.1016 -0.1778)
						)
						(arc
							(start 0.1016 -0.1778)
							(mid 0.137521 -0.162921)
							(end 0.1524 -0.127)
						)
					)
					(width 0)
					(fill yes)
				)
			)
		)
	)
	(footprint ""
		(layer "B.Cu")
		(at 211.2772 -44.7548 90)
		(property "Reference" "C730"
			(at 0 0 90)
			(layer "B.SilkS")
			(hide yes)
			(effects
				(font
					(size 1.27 1.27)
				)
				(justify mirror)
			)
		)
		(property "Value" "SCD22U10V2KX-1GP"
			(at -1.1811 -2.7051 90)
			(unlocked yes)
			(layer "B.Fab")
			(hide yes)
			(effects
				(font
					(size 1.016 1.016)
					(thickness 0.1524)
				)
				(justify mirror)
			)
		)
		(property "Device Type" "C402H22"
			(at -1.1811 -4.2291 90)
			(unlocked yes)
			(layer "B.Fab")
			(hide yes)
			(effects
				(font
					(size 1.016 1.016)
					(thickness 0.1524)
				)
				(justify mirror)
			)
		)
		(duplicate_pad_numbers_are_jumpers no)
		(fp_rect
			(start 0.4318 0.9525)
			(end -0.4318 -0.9525)
			(stroke
				(width 0)
				(type default)
			)
			(fill no)
			(layer "B.CrtYd")
		)
		(fp_rect
			(start 0.4318 0.9525)
			(end -0.4318 -0.9525)
			(stroke
				(width 0)
				(type default)
			)
			(fill no)
			(layer "B.Fab")
		)
		(pad "1" smd custom
			(at 0 -0.4445 270)
			(size 0.1524 0.1524)
			(layers "B.Cu" "B.Mask" "B.Paste")
			(net "BMC_PETXN")
			(options
				(clearance outline)
				(anchor circle)
			)
			(primitives
				(gr_poly
					(pts
						(arc
							(start 0.3048 0.2032)
							(mid 0.275042 0.275042)
							(end 0.2032 0.3048)
						)
						(arc
							(start -0.2032 0.3048)
							(mid -0.275042 0.275042)
							(end -0.3048 0.2032)
						)
						(arc
							(start -0.3048 -0.2032)
							(mid -0.275042 -0.275042)
							(end -0.2032 -0.3048)
						)
						(arc
							(start 0.2032 -0.3048)
							(mid 0.275042 -0.275042)
							(end 0.3048 -0.2032)
						)
					)
					(width 0)
					(fill yes)
				)
			)
		)
		(pad "2" smd custom
			(at 0 0.4445 270)
			(size 0.1524 0.1524)
			(layers "B.Cu" "B.Mask" "B.Paste")
			(net "PCIE_RX_N76")
			(options
				(clearance outline)
				(anchor circle)
			)
			(primitives
				(gr_poly
					(pts
						(arc
							(start 0.3048 0.2032)
							(mid 0.275042 0.275042)
							(end 0.2032 0.3048)
						)
						(arc
							(start -0.2032 0.3048)
							(mid -0.275042 0.275042)
							(end -0.3048 0.2032)
						)
						(arc
							(start -0.3048 -0.2032)
							(mid -0.275042 -0.275042)
							(end -0.2032 -0.3048)
						)
						(arc
							(start 0.2032 -0.3048)
							(mid 0.275042 -0.275042)
							(end 0.3048 -0.2032)
						)
					)
					(width 0)
					(fill yes)
				)
			)
		)
	)
	(footprint ""
		(layer "B.Cu")
		(at 237.1598 -41.995852 90)
		(property "Reference" "C435"
			(at 0 0 90)
			(layer "B.SilkS")
			(hide yes)
			(effects
				(font
					(size 1.27 1.27)
				)
				(justify mirror)
			)
		)
		(property "Value" "SCD1U16V1KX-1-GP"
			(at 2.8321 -1.7399 90)
			(unlocked yes)
			(layer "B.Fab")
			(hide yes)
			(effects
				(font
					(size 1.016 1.016)
					(thickness 0.1524)
				)
				(justify mirror)
			)
		)
		(property "Device Type" "C0201H13"
			(at 2.8321 -3.2639 90)
			(unlocked yes)
			(layer "B.Fab")
			(hide yes)
			(effects
				(font
					(size 1.016 1.016)
					(thickness 0.1524)
				)
				(justify mirror)
			)
		)
		(duplicate_pad_numbers_are_jumpers no)
		(fp_rect
			(start 0.2794 0.6477)
			(end -0.2794 -0.6477)
			(stroke
				(width 0)
				(type default)
			)
			(fill no)
			(layer "B.CrtYd")
		)
		(fp_rect
			(start 0.2794 0.6477)
			(end -0.2794 -0.6477)
			(stroke
				(width 0)
				(type default)
			)
			(fill no)
			(layer "B.Fab")
		)
		(pad "1" smd custom
			(at 0 -0.2794 270)
			(size 0.0762 0.0762)
			(layers "B.Cu" "B.Mask" "B.Paste")
			(net "DUT_VDD")
			(options
				(clearance outline)
				(anchor circle)
			)
			(primitives
				(gr_poly
					(pts
						(arc
							(start 0.1524 0.127)
							(mid 0.137521 0.162921)
							(end 0.1016 0.1778)
						)
						(arc
							(start -0.1016 0.1778)
							(mid -0.137521 0.162921)
							(end -0.1524 0.127)
						)
						(arc
							(start -0.1524 -0.127)
							(mid -0.137521 -0.162921)
							(end -0.1016 -0.1778)
						)
						(arc
							(start 0.1016 -0.1778)
							(mid 0.137521 -0.162921)
							(end 0.1524 -0.127)
						)
					)
					(width 0)
					(fill yes)
				)
			)
		)
		(pad "2" smd custom
			(at 0 0.2794 270)
			(size 0.0762 0.0762)
			(layers "B.Cu" "B.Mask" "B.Paste")
			(net "GND")
			(options
				(clearance outline)
				(anchor circle)
			)
			(primitives
				(gr_poly
					(pts
						(arc
							(start 0.1524 0.127)
							(mid 0.137521 0.162921)
							(end 0.1016 0.1778)
						)
						(arc
							(start -0.1016 0.1778)
							(mid -0.137521 0.162921)
							(end -0.1524 0.127)
						)
						(arc
							(start -0.1524 -0.127)
							(mid -0.137521 -0.162921)
							(end -0.1016 -0.1778)
						)
						(arc
							(start 0.1016 -0.1778)
							(mid 0.137521 -0.162921)
							(end 0.1524 -0.127)
						)
					)
					(width 0)
					(fill yes)
				)
			)
		)
	)
	(footprint ""
		(layer "B.Cu")
		(at 129.4384 -196.3928)
		(property "Reference" "R9030"
			(at 0 0 0)
			(layer "B.SilkS")
			(hide yes)
			(effects
				(font
					(size 1.27 1.27)
				)
				(justify mirror)
			)
		)
		(property "Value" "4K7R2F-GP"
			(at -0.064008 -3.993896 0)
			(unlocked yes)
			(layer "B.Fab")
			(hide yes)
			(effects
				(font
					(size 1.016 1.016)
					(thickness 0.1524)
				)
				(justify mirror)
			)
		)
		(property "Device Type" "R402H16"
			(at -0.064008 -5.517896 0)
			(unlocked yes)
			(layer "B.Fab")
			(hide yes)
			(effects
				(font
					(size 1.016 1.016)
					(thickness 0.1524)
				)
				(justify mirror)
			)
		)
		(duplicate_pad_numbers_are_jumpers no)
		(fp_line
			(start -0.508 -0.9398)
			(end 0.508 -0.9398)
			(stroke
				(width 0.1524)
				(type default)
			)
			(layer "B.SilkS")
		)
		(fp_line
			(start 0.508 -0.9398)
			(end 0.508 0.9398)
			(stroke
				(width 0.1524)
				(type default)
			)
			(layer "B.SilkS")
		)
		(fp_rect
			(start 0.508 0.9398)
			(end -0.508 -0.9398)
			(stroke
				(width 0)
				(type default)
			)
			(fill no)
			(layer "B.CrtYd")
		)
		(fp_rect
			(start 0.508 0.9398)
			(end -0.508 -0.9398)
			(stroke
				(width 0)
				(type default)
			)
			(fill no)
			(layer "B.Fab")
		)
		(pad "1" smd custom
			(at 0 -0.4445 180)
			(size 0.1397 0.1397)
			(layers "B.Cu" "B.Mask" "B.Paste")
			(net "SSD_PERST#1")
			(options
				(clearance outline)
				(anchor circle)
			)
			(primitives
				(gr_poly
					(pts
						(arc
							(start -0.1778 0.2794)
							(mid -0.249642 0.249642)
							(end -0.2794 0.1778)
						)
						(arc
							(start -0.2794 -0.1778)
							(mid -0.249642 -0.249642)
							(end -0.1778 -0.2794)
						)
						(arc
							(start 0.1778 -0.2794)
							(mid 0.249642 -0.249642)
							(end 0.2794 -0.1778)
						)
						(arc
							(start 0.2794 0.1778)
							(mid 0.249642 0.249642)
							(end 0.1778 0.2794)
						)
					)
					(width 0)
					(fill yes)
				)
			)
		)
		(pad "2" smd custom
			(at 0 0.4445 180)
			(size 0.1397 0.1397)
			(layers "B.Cu" "B.Mask" "B.Paste")
			(net "GND")
			(options
				(clearance outline)
				(anchor circle)
			)
			(primitives
				(gr_poly
					(pts
						(arc
							(start -0.1778 0.2794)
							(mid -0.249642 0.249642)
							(end -0.2794 0.1778)
						)
						(arc
							(start -0.2794 -0.1778)
							(mid -0.249642 -0.249642)
							(end -0.1778 -0.2794)
						)
						(arc
							(start 0.1778 -0.2794)
							(mid 0.249642 -0.249642)
							(end 0.2794 -0.1778)
						)
						(arc
							(start 0.2794 0.1778)
							(mid 0.249642 0.249642)
							(end 0.1778 0.2794)
						)
					)
					(width 0)
					(fill yes)
				)
			)
		)
	)
)
